# S9S_MB_2U (Grand Teton) — schematic netlist excerpt (pin names and nets, part order shuffled) for the footprints in the layout excerpt that follows; sources: Cadence DE-HDL packaged netlist, KiCad conversion of 03242023_DA0F0TMBIJ0_F0T_Motherboard_J_brd_V01_OCP.brd

C1663  Q_CAP  0.1UF 25V 10% X7R  pkg 0402  page 155 : A = P3V3_AUX ; B = GND
R700  Q_RES  0 5% CHIP  pkg 0402LF  page 215 : A = FM_ADR_ACK_R ; B = FM_ADR_ACK

(kicad_pcb
	(version 20260206)
	(generator "pcbnew")
	(generator_version "10.0")
	(general
		(thickness 1.6)
		(legacy_teardrops no)
	)
	(paper "A4")
	(title_block
		(title "03242023_DA0F0TMBIJ0_F0T_Motherboard_J_brd_V01_OCP.brd")
		(comment 1 "Grand Teton / footprints 4001-4002 of 6105")
	)
	(layers
		(0 "F.Cu" signal "TOP")
		(4 "In1.Cu" signal "GND")
		(6 "In2.Cu" signal "IN1")
		(8 "In3.Cu" signal "GND1")
		(10 "In4.Cu" signal "IN2")
		(12 "In5.Cu" signal "GND2")
		(14 "In6.Cu" signal "IN3")
		(16 "In7.Cu" signal "GND3")
		(18 "In8.Cu" signal "VCC")
		(20 "In9.Cu" signal "VCC1")
		(22 "In10.Cu" signal "GND4")
		(24 "In11.Cu" signal "IN4")
		(26 "In12.Cu" signal "GND5")
		(28 "In13.Cu" signal "IN5")
		(30 "In14.Cu" signal "GND6")
		(32 "In15.Cu" signal "IN6")
		(34 "In16.Cu" signal "GND7")
		(2 "B.Cu" signal "BOTTOM")
		(9 "F.Adhes" user "F.Adhesive")
		(11 "B.Adhes" user "B.Adhesive")
		(13 "F.Paste" user "Package Geometry/Pastemask Top")
		(15 "B.Paste" user "Package Geometry/Pastemask Bottom")
		(5 "F.SilkS" user "Ref Des/Silkscreen Top")
		(7 "B.SilkS" user "Ref Des/Silkscreen Bottom")
		(1 "F.Mask" user "Board Geometry/Soldermask Top")
		(3 "B.Mask" user "Board Geometry/Soldermask Bottom")
		(17 "Dwgs.User" user "User.Drawings")
		(19 "Cmts.User" user "User.Comments")
		(21 "Eco1.User" user "User.Eco1")
		(23 "Eco2.User" user "User.Eco2")
		(25 "Edge.Cuts" user "Board Geometry/Outline")
		(27 "Margin" user)
		(31 "F.CrtYd" user "Package Geometry/Place Bound Top")
		(29 "B.CrtYd" user "Package Geometry/Place Bound Bottom")
		(35 "F.Fab" user "Ref Des/Assembly Top")
		(33 "B.Fab" user "Ref Des/Assembly Bottom")
	)
	(footprint ""
		(layer "F.Cu")
		(at 308.508654 -13.68044 180)
		(property "Reference" "C1663"
			(at 0 0 180)
			(layer "F.SilkS")
			(hide yes)
			(effects
				(font
					(size 1.27 1.27)
				)
			)
		)
		(property "Value" ""
			(at 0 0 180)
			(layer "F.Fab")
			(effects
				(font
					(size 1.27 1.27)
				)
			)
		)
		(duplicate_pad_numbers_are_jumpers no)
		(fp_line
			(start 0.7874 0.4064)
			(end -0.7874 0.4064)
			(stroke
				(width 0.1524)
				(type default)
			)
			(layer "F.SilkS")
		)
		(fp_line
			(start 0.7874 -0.4064)
			(end 0.7874 0.4064)
			(stroke
				(width 0.1524)
				(type default)
			)
			(layer "F.SilkS")
		)
		(fp_line
			(start -0.7874 0.4064)
			(end -0.7874 -0.4064)
			(stroke
				(width 0.1524)
				(type default)
			)
			(layer "F.SilkS")
		)
		(fp_line
			(start -0.7874 -0.4064)
			(end 0.7874 -0.4064)
			(stroke
				(width 0.1524)
				(type default)
			)
			(layer "F.SilkS")
		)
		(fp_line
			(start 0.67945 0.3048)
			(end 0.120396 0.3048)
			(stroke
				(width 0.1)
				(type default)
			)
			(layer "F.Fab")
		)
		(fp_line
			(start 0.67945 -0.3048)
			(end 0.67945 0.3048)
			(stroke
				(width 0.1)
				(type default)
			)
			(layer "F.Fab")
		)
		(fp_line
			(start 0.12065 -0.2794)
			(end 0.12065 -0.3048)
			(stroke
				(width 0.1)
				(type default)
			)
			(layer "F.Fab")
		)
		(fp_line
			(start 0.12065 -0.3048)
			(end 0.67945 -0.3048)
			(stroke
				(width 0.1)
				(type default)
			)
			(layer "F.Fab")
		)
		(fp_line
			(start 0.120396 0.3048)
			(end 0.120396 0.2794)
			(stroke
				(width 0.1)
				(type default)
			)
			(layer "F.Fab")
		)
		(fp_line
			(start 0.120396 0.2794)
			(end -0.12065 0.2794)
			(stroke
				(width 0.1)
				(type default)
			)
			(layer "F.Fab")
		)
		(fp_line
			(start -0.12065 0.3048)
			(end -0.67945 0.3048)
			(stroke
				(width 0.1)
				(type default)
			)
			(layer "F.Fab")
		)
		(fp_line
			(start -0.12065 0.2794)
			(end -0.12065 0.3048)
			(stroke
				(width 0.1)
				(type default)
			)
			(layer "F.Fab")
		)
		(fp_line
			(start -0.12065 -0.2794)
			(end 0.12065 -0.2794)
			(stroke
				(width 0.1)
				(type default)
			)
			(layer "F.Fab")
		)
		(fp_line
			(start -0.12065 -0.305054)
			(end -0.12065 -0.2794)
			(stroke
				(width 0.1)
				(type default)
			)
			(layer "F.Fab")
		)
		(fp_line
			(start -0.67945 0.3048)
			(end -0.67945 -0.305054)
			(stroke
				(width 0.1)
				(type default)
			)
			(layer "F.Fab")
		)
		(fp_line
			(start -0.67945 -0.305054)
			(end -0.12065 -0.305054)
			(stroke
				(width 0.1)
				(type default)
			)
			(layer "F.Fab")
		)
		(pad "1" smd circle
			(at -0.40005 0 180)
			(size 0 0)
			(layers "F.Cu" "F.Mask" "F.Paste")
			(net "P3V3_AUX")
		)
		(pad "2" smd circle
			(at 0.40005 0 180)
			(size 0 0)
			(layers "F.Cu" "F.Mask" "F.Paste")
			(net "GND")
		)
	)
	(footprint ""
		(layer "F.Cu")
		(at 193.60388 -99.875848)
		(property "Reference" "R700"
			(at 0 0 0)
			(layer "F.SilkS")
			(hide yes)
			(effects
				(font
					(size 1.27 1.27)
				)
			)
		)
		(property "Value" ""
			(at 0 0 0)
			(layer "F.Fab")
			(effects
				(font
					(size 1.27 1.27)
				)
			)
		)
		(duplicate_pad_numbers_are_jumpers no)
		(fp_line
			(start -0.7874 -0.4064)
			(end 0.7874 -0.4064)
			(stroke
				(width 0.1524)
				(type default)
			)
			(layer "F.SilkS")
		)
		(fp_line
			(start -0.7874 0.4064)
			(end -0.7874 -0.4064)
			(stroke
				(width 0.1524)
				(type default)
			)
			(layer "F.SilkS")
		)
		(fp_line
			(start 0.7874 -0.4064)
			(end 0.7874 0.4064)
			(stroke
				(width 0.1524)
				(type default)
			)
			(layer "F.SilkS")
		)
		(fp_line
			(start 0.7874 0.4064)
			(end -0.7874 0.4064)
			(stroke
				(width 0.1524)
				(type default)
			)
			(layer "F.SilkS")
		)
		(fp_line
			(start -0.67945 -0.305054)
			(end -0.12065 -0.305054)
			(stroke
				(width 0.1)
				(type default)
			)
			(layer "F.Fab")
		)
		(fp_line
			(start -0.67945 0.3048)
			(end -0.67945 -0.305054)
			(stroke
				(width 0.1)
				(type default)
			)
			(layer "F.Fab")
		)
		(fp_line
			(start -0.12065 -0.305054)
			(end -0.12065 -0.2794)
			(stroke
				(width 0.1)
				(type default)
			)
			(layer "F.Fab")
		)
		(fp_line
			(start -0.12065 -0.2794)
			(end 0.12065 -0.2794)
			(stroke
				(width 0.1)
				(type default)
			)
			(layer "F.Fab")
		)
		(fp_line
			(start -0.12065 0.2794)
			(end -0.12065 0.3048)
			(stroke
				(width 0.1)
				(type default)
			)
			(layer "F.Fab")
		)
		(fp_line
			(start -0.12065 0.3048)
			(end -0.67945 0.3048)
			(stroke
				(width 0.1)
				(type default)
			)
			(layer "F.Fab")
		)
		(fp_line
			(start 0.120396 0.2794)
			(end -0.12065 0.2794)
			(stroke
				(width 0.1)
				(type default)
			)
			(layer "F.Fab")
		)
		(fp_line
			(start 0.120396 0.3048)
			(end 0.120396 0.2794)
			(stroke
				(width 0.1)
				(type default)
			)
			(layer "F.Fab")
		)
		(fp_line
			(start 0.12065 -0.3048)
			(end 0.67945 -0.3048)
			(stroke
				(width 0.1)
				(type default)
			)
			(layer "F.Fab")
		)
		(fp_line
			(start 0.12065 -0.2794)
			(end 0.12065 -0.3048)
			(stroke
				(width 0.1)
				(type default)
			)
			(layer "F.Fab")
		)
		(fp_line
			(start 0.67945 -0.3048)
			(end 0.67945 0.3048)
			(stroke
				(width 0.1)
				(type default)
			)
			(layer "F.Fab")
		)
		(fp_line
			(start 0.67945 0.3048)
			(end 0.120396 0.3048)
			(stroke
				(width 0.1)
				(type default)
			)
			(layer "F.Fab")
		)
		(pad "1" smd circle
			(at -0.40005 0)
			(size 0 0)
			(layers "F.Cu" "F.Mask" "F.Paste")
			(net "FM_ADR_ACK_R")
		)
		(pad "2" smd circle
			(at 0.40005 0)
			(size 0 0)
			(layers "F.Cu" "F.Mask" "F.Paste")
			(net "FM_ADR_ACK")
		)
	)
)
